(kicad_pcb
	(version 20241229)
	(generator "pcbnew")
	(generator_version "9.0")
	(general
		(thickness 1.711)
		(legacy_teardrops no)
	)
	(paper "A4")
	(title_block
		(title "Antmicro Baseboard for Jetson AGX Thor")
		(date "2026-02-18")
		(rev "1.1.0")
		(company "Antmicro Ltd")
		(comment 1 "www.antmicro.com")
		(comment 9 "footprints 680-684 of 1170")
	)
	(layers
		(0 "F.Cu" signal)
		(4 "In1.Cu" signal)
		(6 "In2.Cu" signal)
		(8 "In3.Cu" signal)
		(10 "In4.Cu" jumper)
		(12 "In5.Cu" signal)
		(14 "In6.Cu" signal)
		(16 "In7.Cu" signal)
		(18 "In8.Cu" signal)
		(2 "B.Cu" signal)
		(9 "F.Adhes" user "F.Adhesive")
		(11 "B.Adhes" user "B.Adhesive")
		(13 "F.Paste" user)
		(15 "B.Paste" user)
		(5 "F.SilkS" user "F.Silkscreen")
		(7 "B.SilkS" user "B.Silkscreen")
		(1 "F.Mask" user)
		(3 "B.Mask" user)
		(17 "Dwgs.User" user "User.Drawings")
		(19 "Cmts.User" user "User.Comments")
		(21 "Eco1.User" user "User.Eco1")
		(23 "Eco2.User" user "User.Eco2")
		(25 "Edge.Cuts" user)
		(27 "Margin" user)
		(31 "F.CrtYd" user "F.Courtyard")
		(29 "B.CrtYd" user "B.Courtyard")
		(35 "F.Fab" user)
		(33 "B.Fab" user)
	)
	(footprint "antmicro-footprints:C_0402_1005Metric"
		(layer "B.Cu")
		(at 220.3 82.3 -90)
		(descr "Capacitor SMD 0402")
		(tags "capacitor SMD 0402")
		(property "Reference" "C44"
			(at 0.9 -0.5 90)
			(layer "B.SilkS")
			(effects
				(font
					(size 0.7 0.7)
					(thickness 0.15)
				)
				(justify left bottom mirror)
			)
		)
		(property "Value" "C_100n_0402"
			(at -1.022927 -2.155213 90)
			(layer "B.Fab")
			(effects
				(font
					(size 0.7 0.7)
					(thickness 0.15)
				)
				(justify left bottom mirror)
			)
		)
		(property "Datasheet" "https://www.murata.com/products/productdetail?partno=GRM155R61H104KE14%23"
			(at 0 0 90)
			(layer "B.Fab")
			(hide yes)
			(effects
				(font
					(size 1.27 1.27)
					(thickness 0.15)
				)
				(justify mirror)
			)
		)
		(property "Description" "SMD Multilayer Ceramic Capacitor, 0.1 µF, 50 V, 0402 [1005 Metric], ± 10%, X5R, GRM Series"
			(at 0 0 90)
			(layer "B.Fab")
			(hide yes)
			(effects
				(font
					(size 1.27 1.27)
					(thickness 0.15)
				)
				(justify mirror)
			)
		)
		(property "Manufacturer" "Murata"
			(at 0 0 90)
			(unlocked yes)
			(layer "B.Fab")
			(hide yes)
			(effects
				(font
					(size 1 1)
					(thickness 0.15)
				)
				(justify mirror)
			)
		)
		(property "MPN" "GRM155R61H104KE14D"
			(at 0 0 90)
			(unlocked yes)
			(layer "B.Fab")
			(hide yes)
			(effects
				(font
					(size 1 1)
					(thickness 0.15)
				)
				(justify mirror)
			)
		)
		(property "Val" "100n"
			(at 0 0 90)
			(unlocked yes)
			(layer "B.Fab")
			(hide yes)
			(effects
				(font
					(size 1 1)
					(thickness 0.15)
				)
				(justify mirror)
			)
		)
		(property "License" "Apache-2.0"
			(at 0 0 90)
			(unlocked yes)
			(layer "B.Fab")
			(hide yes)
			(effects
				(font
					(size 1 1)
					(thickness 0.15)
				)
				(justify mirror)
			)
		)
		(property "Author" "Antmicro"
			(at 0 0 90)
			(unlocked yes)
			(layer "B.Fab")
			(hide yes)
			(effects
				(font
					(size 1 1)
					(thickness 0.15)
				)
				(justify mirror)
			)
		)
		(property "Voltage" "50V"
			(at 0 0 90)
			(unlocked yes)
			(layer "B.Fab")
			(hide yes)
			(effects
				(font
					(size 1 1)
					(thickness 0.15)
				)
				(justify mirror)
			)
		)
		(property "Dielectric" "X5R"
			(at 0 0 90)
			(unlocked yes)
			(layer "B.Fab")
			(hide yes)
			(effects
				(font
					(size 1 1)
					(thickness 0.15)
				)
				(justify mirror)
			)
		)
		(sheetname "/USB Debug, PD/")
		(sheetfile "usb_debug_pd.kicad_sch")
		(attr smd)
		(fp_poly
			(pts
				(xy -0.925 0.47) (xy 0.925 0.47) (xy 0.925 -0.47) (xy -0.925 -0.47)
			)
			(stroke
				(width 0.05)
				(type default)
			)
			(fill no)
			(layer "B.CrtYd")
		)
		(fp_line
			(start -0.494 0.25)
			(end 0.504 0.25)
			(stroke
				(width 0.15)
				(type solid)
			)
			(layer "B.Fab")
		)
		(fp_line
			(start 0.504 0.25)
			(end 0.504 -0.248)
			(stroke
				(width 0.15)
				(type solid)
			)
			(layer "B.Fab")
		)
		(fp_line
			(start -0.494 -0.248)
			(end -0.494 0.25)
			(stroke
				(width 0.15)
				(type solid)
			)
			(layer "B.Fab")
		)
		(fp_line
			(start 0.504 -0.248)
			(end -0.494 -0.248)
			(stroke
				(width 0.15)
				(type solid)
			)
			(layer "B.Fab")
		)
		(fp_text user "License: Apache-2.0"
			(at -0.939 -5.799 90)
			(layer "B.Fab")
			(effects
				(font
					(size 0.7 0.7)
					(thickness 0.15)
				)
				(justify left bottom mirror)
			)
		)
		(fp_text user "${REFERENCE}"
			(at -0.939 -4.599 90)
			(layer "B.Fab")
			(effects
				(font
					(size 0.7 0.7)
					(thickness 0.15)
				)
				(justify left bottom mirror)
			)
		)
		(fp_text user "Author: Antmicro"
			(at -0.939 -3.399 90)
			(layer "B.Fab")
			(effects
				(font
					(size 0.7 0.7)
					(thickness 0.15)
				)
				(justify left bottom mirror)
			)
		)
		(pad "1" smd roundrect
			(at -0.48 0 270)
			(size 0.59 0.64)
			(layers "B.Cu" "B.Mask" "B.Paste")
			(roundrect_rratio 0.25)
			(net 334 "/USB Debug, PD/FTDI_3V3")
			(pintype "passive")
		)
		(pad "2" smd roundrect
			(at 0.48 0 270)
			(size 0.59 0.64)
			(layers "B.Cu" "B.Mask" "B.Paste")
			(roundrect_rratio 0.25)
			(net 1 "GND")
			(pintype "passive")
		)
	)
	(footprint "antmicro-footprints:C_0603_1608Metric_EIA"
		(layer "B.Cu")
		(at 112.11 69.49 180)
		(descr "Capacitor SMD 0603, IPC-7351 Density Level A")
		(tags "Capacitor 0603")
		(property "Reference" "C19"
			(at -1.09 0.89 0)
			(layer "B.SilkS")
			(effects
				(font
					(size 0.7 0.7)
					(thickness 0.15)
				)
				(justify left bottom mirror)
			)
		)
		(property "Value" "C_22u_16V_0603"
			(at -1.42757 -1.770288 0)
			(layer "B.Fab")
			(effects
				(font
					(size 0.7 0.7)
					(thickness 0.15)
				)
				(justify left bottom mirror)
			)
		)
		(property "Datasheet" "https://product.samsungsem.com/mlcc/CL10A226MO7JZN.do"
			(at 0 0 0)
			(layer "B.Fab")
			(hide yes)
			(effects
				(font
					(size 1.27 1.27)
					(thickness 0.15)
				)
				(justify mirror)
			)
		)
		(property "Description" "SMD Multilayer Ceramic Capacitor"
			(at 0 0 0)
			(layer "B.Fab")
			(hide yes)
			(effects
				(font
					(size 1.27 1.27)
					(thickness 0.15)
				)
				(justify mirror)
			)
		)
		(property "MPN" "CL10A226MO7JZNC"
			(at 0 0 180)
			(unlocked yes)
			(layer "B.Fab")
			(hide yes)
			(effects
				(font
					(size 1 1)
					(thickness 0.15)
				)
				(justify mirror)
			)
		)
		(property "Manufacturer" "Samsung Electro-Mechanics"
			(at 0 0 180)
			(unlocked yes)
			(layer "B.Fab")
			(hide yes)
			(effects
				(font
					(size 1 1)
					(thickness 0.15)
				)
				(justify mirror)
			)
		)
		(property "License" "Apache-2.0"
			(at 0 0 180)
			(unlocked yes)
			(layer "B.Fab")
			(hide yes)
			(effects
				(font
					(size 1 1)
					(thickness 0.15)
				)
				(justify mirror)
			)
		)
		(property "Author" "Antmicro"
			(at 0 0 180)
			(unlocked yes)
			(layer "B.Fab")
			(hide yes)
			(effects
				(font
					(size 1 1)
					(thickness 0.15)
				)
				(justify mirror)
			)
		)
		(property "Val" "22u"
			(at 0 0 180)
			(unlocked yes)
			(layer "B.Fab")
			(hide yes)
			(effects
				(font
					(size 1 1)
					(thickness 0.15)
				)
				(justify mirror)
			)
		)
		(property "Voltage" "16V"
			(at 0 0 180)
			(unlocked yes)
			(layer "B.Fab")
			(hide yes)
			(effects
				(font
					(size 1 1)
					(thickness 0.15)
				)
				(justify mirror)
			)
		)
		(property "Dielectric" "X7R"
			(at 0 0 180)
			(unlocked yes)
			(layer "B.Fab")
			(hide yes)
			(effects
				(font
					(size 1 1)
					(thickness 0.15)
				)
				(justify mirror)
			)
		)
		(property "Public" "False"
			(at 0 0 180)
			(unlocked yes)
			(layer "B.Fab")
			(hide yes)
			(effects
				(font
					(size 1 1)
					(thickness 0.15)
				)
				(justify mirror)
			)
		)
		(sheetname "/SoM_Power/")
		(sheetfile "som_power.kicad_sch")
		(attr smd)
		(fp_line
			(start -0.15 0.55)
			(end 0.15 0.55)
			(stroke
				(width 0.15)
				(type solid)
			)
			(layer "B.SilkS")
		)
		(fp_line
			(start -0.15 -0.55)
			(end 0.15 -0.55)
			(stroke
				(width 0.15)
				(type solid)
			)
			(layer "B.SilkS")
		)
		(fp_rect
			(start -1.25 0.65)
			(end 1.25 -0.65)
			(stroke
				(width 0.05)
				(type solid)
			)
			(fill no)
			(layer "B.CrtYd")
		)
		(fp_rect
			(start -0.8 0.45)
			(end 0.8 -0.45)
			(stroke
				(width 0.15)
				(type solid)
			)
			(fill no)
			(layer "B.Fab")
		)
		(fp_text user "${REFERENCE}"
			(at -1.682 -3.895 0)
			(layer "B.Fab")
			(effects
				(font
					(size 0.7 0.7)
					(thickness 0.15)
				)
				(justify left bottom mirror)
			)
		)
		(fp_text user "Author: Antmicro"
			(at -1.682 -4.894 0)
			(layer "B.Fab")
			(effects
				(font
					(size 0.7 0.7)
					(thickness 0.15)
				)
				(justify left bottom mirror)
			)
		)
		(fp_text user "License: Apache-2.0"
			(at -1.682 -5.895 0)
			(layer "B.Fab")
			(effects
				(font
					(size 0.7 0.7)
					(thickness 0.15)
				)
				(justify left bottom mirror)
			)
		)
		(pad "1" smd roundrect
			(at -0.7 0 180)
			(size 0.8 1.1)
			(layers "B.Cu" "B.Mask" "B.Paste")
			(roundrect_rratio 0.2)
			(net 1 "GND")
			(pintype "passive")
		)
		(pad "2" smd roundrect
			(at 0.7 0 180)
			(size 0.8 1.1)
			(layers "B.Cu" "B.Mask" "B.Paste")
			(roundrect_rratio 0.2)
			(net 213 "+5V_SOM")
			(pintype "passive")
		)
	)
	(footprint "antmicro-footprints:Fiducial_1mm_Mask3mm"
		(layer "B.Cu")
		(at 65.9 55.63 180)
		(descr "Circular Fiducial, 1.5mm bare copper, 3mm soldermask opening")
		(tags "fiducial")
		(property "Reference" "FD8"
			(at 1.52 -0.43 0)
			(layer "B.SilkS")
			(effects
				(font
					(size 0.7 0.7)
					(thickness 0.15)
				)
				(justify left bottom mirror)
			)
		)
		(property "Value" "Fiducial_1mm_Mask3mm"
			(at 0 -2.603 0)
			(layer "B.Fab")
			(effects
				(font
					(size 0.7 0.7)
					(thickness 0.15)
				)
				(justify left bottom mirror)
			)
		)
		(property "Description" "Fiducial mask"
			(at 0 0 0)
			(layer "B.Fab")
			(hide yes)
			(effects
				(font
					(size 1.27 1.27)
					(thickness 0.15)
				)
				(justify mirror)
			)
		)
		(property "Author" "Antmicro"
			(at 0 0 0)
			(unlocked yes)
			(layer "B.Fab")
			(hide yes)
			(effects
				(font
					(size 1 1)
					(thickness 0.15)
				)
				(justify mirror)
			)
		)
		(property "License" "Apache-2.0"
			(at 0 0 0)
			(unlocked yes)
			(layer "B.Fab")
			(hide yes)
			(effects
				(font
					(size 1 1)
					(thickness 0.15)
				)
				(justify mirror)
			)
		)
		(sheetname "/")
		(sheetfile "jetson-agx-thor-baseboard.kicad_sch")
		(attr exclude_from_pos_files exclude_from_bom)
		(fp_circle
			(center 0 0)
			(end 1.5 0)
			(stroke
				(width 0.05)
				(type solid)
			)
			(fill no)
			(layer "B.CrtYd")
		)
		(fp_circle
			(center 0 0)
			(end 1.5 0)
			(stroke
				(width 0.15)
				(type solid)
			)
			(fill no)
			(layer "B.Fab")
		)
		(fp_text user "License: Apache-2.0"
			(at -1.25 -7.003 0)
			(layer "B.Fab")
			(effects
				(font
					(size 0.7 0.7)
					(thickness 0.15)
				)
				(justify left bottom mirror)
			)
		)
		(fp_text user "${REFERENCE}"
			(at -1.25 -4.603 0)
			(layer "B.Fab")
			(effects
				(font
					(size 0.7 0.7)
					(thickness 0.15)
				)
				(justify left bottom mirror)
			)
		)
		(fp_text user "Author: Antmicro"
			(at -1.25 -5.803 0)
			(layer "B.Fab")
			(effects
				(font
					(size 0.7 0.7)
					(thickness 0.15)
				)
				(justify left bottom mirror)
			)
		)
		(pad "" smd circle
			(at 0 0 180)
			(size 1 1)
			(layers "B.Cu" "B.Mask")
			(solder_mask_margin 1)
			(clearance 1)
		)
	)
	(footprint "antmicro-footprints:TP_SMD_0.75mm"
		(layer "B.Cu")
		(at 88 65.9)
		(property "Reference" "TP103"
			(at -2.2 -1.3 0)
			(layer "B.SilkS")
			(effects
				(font
					(size 0.7 0.7)
					(thickness 0.15)
				)
				(justify right top mirror)
			)
		)
		(property "Value" "TP_0.75mm_SMD"
			(at 0 -1.2 0)
			(layer "B.Fab")
			(effects
				(font
					(size 0.7 0.7)
					(thickness 0.15)
				)
				(justify right top mirror)
			)
		)
		(property "Description" "SMT test point"
			(at 0 0 0)
			(layer "B.Fab")
			(hide yes)
			(effects
				(font
					(size 1.27 1.27)
					(thickness 0.15)
				)
				(justify mirror)
			)
		)
		(property "MPN" ""
			(at 0 0 180)
			(unlocked yes)
			(layer "B.Fab")
			(hide yes)
			(effects
				(font
					(size 1 1)
					(thickness 0.15)
				)
				(justify mirror)
			)
		)
		(property "Manufacturer" ""
			(at 0 0 180)
			(unlocked yes)
			(layer "B.Fab")
			(hide yes)
			(effects
				(font
					(size 1 1)
					(thickness 0.15)
				)
				(justify mirror)
			)
		)
		(property "Author" "Antmicro"
			(at 0 0 180)
			(unlocked yes)
			(layer "B.Fab")
			(hide yes)
			(effects
				(font
					(size 1 1)
					(thickness 0.15)
				)
				(justify mirror)
			)
		)
		(property "License" "Apache-2.0"
			(at 0 0 180)
			(unlocked yes)
			(layer "B.Fab")
			(hide yes)
			(effects
				(font
					(size 1 1)
					(thickness 0.15)
				)
				(justify mirror)
			)
		)
		(sheetname "/SoM_IO/")
		(sheetfile "som_io.kicad_sch")
		(attr exclude_from_pos_files exclude_from_bom)
		(fp_circle
			(center 0 0)
			(end 0.475 0)
			(stroke
				(width 0.05)
				(type default)
			)
			(fill no)
			(layer "B.CrtYd")
		)
		(fp_text user "${REFERENCE}"
			(at -0.4 -2.7 0)
			(layer "B.Fab")
			(effects
				(font
					(size 0.7 0.7)
					(thickness 0.15)
				)
				(justify right top mirror)
			)
		)
		(fp_text user "Author: Antmicro"
			(at -0.4 -3.901 0)
			(layer "B.Fab")
			(effects
				(font
					(size 0.7 0.7)
					(thickness 0.15)
				)
				(justify right top mirror)
			)
		)
		(fp_text user "License: Apache-2.0"
			(at -0.4 -5.101 0)
			(layer "B.Fab")
			(effects
				(font
					(size 0.7 0.7)
					(thickness 0.15)
				)
				(justify right top mirror)
			)
		)
		(pad "1" smd circle
			(at 0 0)
			(size 0.75 0.75)
			(layers "B.Cu" "B.Mask")
			(net 48 "/SoM_IO/I2C1_SCL_1V8")
			(pinfunction "1")
			(pintype "passive")
		)
	)
	(footprint "antmicro-footprints:R_0402_1005Metric"
		(layer "B.Cu")
		(at 61.2 66.5 -90)
		(descr "Resistor SMD 0402")
		(tags "resistor SMD 0402")
		(property "Reference" "R391"
			(at -9.7 0 90)
			(layer "B.SilkS")
			(effects
				(font
					(size 0.7 0.7)
					(thickness 0.15)
				)
				(justify left bottom mirror)
			)
		)
		(property "Value" "R_2k2_0402"
			(at -1.011843 -1.772047 90)
			(layer "B.Fab")
			(effects
				(font
					(size 0.7 0.7)
					(thickness 0.15)
				)
				(justify left bottom mirror)
			)
		)
		(property "Datasheet" "https://www.bourns.com/docs/product-datasheets/cr.pdf"
			(at 0 0 90)
			(layer "B.Fab")
			(hide yes)
			(effects
				(font
					(size 1.27 1.27)
					(thickness 0.15)
				)
				(justify mirror)
			)
		)
		(property "Description" "SMD Chip Resistor, 2.2 kohm, ± 1%, 62.5 mW, 0402 [1005 Metric], Thick Film, General Purpose"
			(at 0 0 90)
			(layer "B.Fab")
			(hide yes)
			(effects
				(font
					(size 1.27 1.27)
					(thickness 0.15)
				)
				(justify mirror)
			)
		)
		(property "MPN" "CR0402-FX-2201GLF"
			(at 0 0 90)
			(unlocked yes)
			(layer "B.Fab")
			(hide yes)
			(effects
				(font
					(size 1 1)
					(thickness 0.15)
				)
				(justify mirror)
			)
		)
		(property "Manufacturer" "Bourns"
			(at 0 0 90)
			(unlocked yes)
			(layer "B.Fab")
			(hide yes)
			(effects
				(font
					(size 1 1)
					(thickness 0.15)
				)
				(justify mirror)
			)
		)
		(property "License" "Apache-2.0"
			(at 0 0 90)
			(unlocked yes)
			(layer "B.Fab")
			(hide yes)
			(effects
				(font
					(size 1 1)
					(thickness 0.15)
				)
				(justify mirror)
			)
		)
		(property "Author" "Antmicro"
			(at 0 0 90)
			(unlocked yes)
			(layer "B.Fab")
			(hide yes)
			(effects
				(font
					(size 1 1)
					(thickness 0.15)
				)
				(justify mirror)
			)
		)
		(property "Val" "2k2"
			(at 0 0 90)
			(unlocked yes)
			(layer "B.Fab")
			(hide yes)
			(effects
				(font
					(size 1 1)
					(thickness 0.15)
				)
				(justify mirror)
			)
		)
		(property "Tolerance" "1%"
			(at 0 0 90)
			(unlocked yes)
			(layer "B.Fab")
			(hide yes)
			(effects
				(font
					(size 1 1)
					(thickness 0.15)
				)
				(justify mirror)
			)
		)
		(sheetname "/CSI/")
		(sheetfile "csi.kicad_sch")
		(attr smd)
		(fp_rect
			(start -0.925 0.47)
			(end 0.925 -0.47)
			(stroke
				(width 0.05)
				(type default)
			)
			(fill no)
			(layer "B.CrtYd")
		)
		(fp_rect
			(start -0.5 0.25)
			(end 0.5 -0.25)
			(stroke
				(width 0.15)
				(type solid)
			)
			(fill no)
			(layer "B.Fab")
		)
		(fp_text user "Author: Antmicro"
			(at -0.95 -4.169 90)
			(layer "B.Fab")
			(effects
				(font
					(size 0.7 0.7)
					(thickness 0.15)
				)
				(justify left bottom mirror)
			)
		)
		(fp_text user "${REFERENCE}"
			(at -0.95 -3.168 90)
			(layer "B.Fab")
			(effects
				(font
					(size 0.7 0.7)
					(thickness 0.15)
				)
				(justify left bottom mirror)
			)
		)
		(fp_text user "License: Apache-2.0"
			(at -0.95 -5.169 90)
			(layer "B.Fab")
			(effects
				(font
					(size 0.7 0.7)
					(thickness 0.15)
				)
				(justify left bottom mirror)
			)
		)
		(pad "1" smd roundrect
			(at -0.48 0 270)
			(size 0.59 0.64)
			(layers "B.Cu" "B.Mask" "B.Paste")
			(roundrect_rratio 0.25)
			(net 979 "/CSI/CSIA_I2C_VCC")
			(pintype "passive")
		)
		(pad "2" smd roundrect
			(at 0.48 0 270)
			(size 0.59 0.64)
			(layers "B.Cu" "B.Mask" "B.Paste")
			(roundrect_rratio 0.25)
			(net 987 "/CSI/SDA_CAM0")
			(pintype "passive")
		)
	)
)
